# S9S_MB_2U (Grand Teton) — schematic netlist excerpt (pin names and nets, part order shuffled) for the footprints in the layout excerpt that follows; sources: Cadence DE-HDL packaged netlist, KiCad conversion of 03242023_DA0F0TMBIJ0_F0T_Motherboard_J_brd_V01_OCP.brd

R128  Q_RES  0 5% CHIP  pkg 0402LF  page 125 : A = PWRGD_DRAMPWRGD_CPU1_GH_R_LVC1 ; B = PWRGD_DRAMPWRGD_CPU1_GH_LVC1_R2
C455  Q_CAP  47UF 4V 20% X6S  pkg C0805  page 79 : A = PVCCD_HV_CPU1 ; B = GND
C1827  Q_CAP  0.1UF 25V 10% X7R  pkg 0402  page 160 : A = P3V3_AUX ; B = GND

(kicad_pcb
	(version 20260206)
	(generator "pcbnew")
	(generator_version "10.0")
	(general
		(thickness 1.6)
		(legacy_teardrops no)
	)
	(paper "A4")
	(title_block
		(title "03242023_DA0F0TMBIJ0_F0T_Motherboard_J_brd_V01_OCP.brd")
		(comment 1 "Grand Teton / footprints 5437-5439 of 6105")
	)
	(layers
		(0 "F.Cu" signal "TOP")
		(4 "In1.Cu" signal "GND")
		(6 "In2.Cu" signal "IN1")
		(8 "In3.Cu" signal "GND1")
		(10 "In4.Cu" signal "IN2")
		(12 "In5.Cu" signal "GND2")
		(14 "In6.Cu" signal "IN3")
		(16 "In7.Cu" signal "GND3")
		(18 "In8.Cu" signal "VCC")
		(20 "In9.Cu" signal "VCC1")
		(22 "In10.Cu" signal "GND4")
		(24 "In11.Cu" signal "IN4")
		(26 "In12.Cu" signal "GND5")
		(28 "In13.Cu" signal "IN5")
		(30 "In14.Cu" signal "GND6")
		(32 "In15.Cu" signal "IN6")
		(34 "In16.Cu" signal "GND7")
		(2 "B.Cu" signal "BOTTOM")
		(9 "F.Adhes" user "F.Adhesive")
		(11 "B.Adhes" user "B.Adhesive")
		(13 "F.Paste" user "Package Geometry/Pastemask Top")
		(15 "B.Paste" user "Package Geometry/Pastemask Bottom")
		(5 "F.SilkS" user "Ref Des/Silkscreen Top")
		(7 "B.SilkS" user "Ref Des/Silkscreen Bottom")
		(1 "F.Mask" user "Board Geometry/Soldermask Top")
		(3 "B.Mask" user "Board Geometry/Soldermask Bottom")
		(17 "Dwgs.User" user "User.Drawings")
		(19 "Cmts.User" user "User.Comments")
		(21 "Eco1.User" user "User.Eco1")
		(23 "Eco2.User" user "User.Eco2")
		(25 "Edge.Cuts" user "Board Geometry/Outline")
		(27 "Margin" user)
		(31 "F.CrtYd" user "Package Geometry/Place Bound Top")
		(29 "B.CrtYd" user "Package Geometry/Place Bound Bottom")
		(35 "F.Fab" user "Ref Des/Assembly Top")
		(33 "B.Fab" user "Ref Des/Assembly Bottom")
	)
	(footprint ""
		(layer "B.Cu")
		(at 111.310928 -210.194144)
		(property "Reference" "C455"
			(at 0 0 0)
			(layer "B.SilkS")
			(hide yes)
			(effects
				(font
					(size 1.27 1.27)
				)
				(justify mirror)
			)
		)
		(property "Value" ""
			(at 0 0 0)
			(layer "B.Fab")
			(effects
				(font
					(size 1.27 1.27)
				)
				(justify mirror)
			)
		)
		(duplicate_pad_numbers_are_jumpers no)
		(fp_line
			(start -1.524 -0.762)
			(end -1.524 0.762)
			(stroke
				(width 0.1524)
				(type default)
			)
			(layer "B.SilkS")
		)
		(fp_line
			(start -1.524 0.762)
			(end 1.524 0.762)
			(stroke
				(width 0.1524)
				(type default)
			)
			(layer "B.SilkS")
		)
		(fp_line
			(start 1.524 -0.762)
			(end -1.524 -0.762)
			(stroke
				(width 0.1524)
				(type default)
			)
			(layer "B.SilkS")
		)
		(fp_line
			(start 1.524 0.762)
			(end 1.524 -0.762)
			(stroke
				(width 0.1524)
				(type default)
			)
			(layer "B.SilkS")
		)
		(fp_line
			(start -1.1049 -0.724916)
			(end 1.1049 -0.724916)
			(stroke
				(width 0.1)
				(type default)
			)
			(layer "B.Fab")
		)
		(fp_line
			(start -1.1049 0.724916)
			(end -1.1049 -0.724916)
			(stroke
				(width 0.1)
				(type default)
			)
			(layer "B.Fab")
		)
		(fp_line
			(start 1.1049 -0.724916)
			(end 1.1049 0.724916)
			(stroke
				(width 0.1)
				(type default)
			)
			(layer "B.Fab")
		)
		(fp_line
			(start 1.1049 0.724916)
			(end -1.1049 0.724916)
			(stroke
				(width 0.1)
				(type default)
			)
			(layer "B.Fab")
		)
		(pad "1" smd rect
			(at 0.889 0)
			(size 1.016 1.27)
			(layers "B.Cu" "B.Mask" "B.Paste")
			(net "PVCCD_HV_CPU1")
		)
		(pad "2" smd rect
			(at -0.889 0)
			(size 1.016 1.27)
			(layers "B.Cu" "B.Mask" "B.Paste")
			(net "GND")
		)
	)
	(footprint ""
		(layer "B.Cu")
		(at 205.434438 -110.47095 -90)
		(property "Reference" "R128"
			(at 0 0 90)
			(layer "B.SilkS")
			(hide yes)
			(effects
				(font
					(size 1.27 1.27)
				)
				(justify mirror)
			)
		)
		(property "Value" ""
			(at 0 0 90)
			(layer "B.Fab")
			(effects
				(font
					(size 1.27 1.27)
				)
				(justify mirror)
			)
		)
		(duplicate_pad_numbers_are_jumpers no)
		(fp_line
			(start -0.7874 0.4064)
			(end 0.7874 0.4064)
			(stroke
				(width 0.1524)
				(type default)
			)
			(layer "B.SilkS")
		)
		(fp_line
			(start 0.7874 0.4064)
			(end 0.7874 -0.4064)
			(stroke
				(width 0.1524)
				(type default)
			)
			(layer "B.SilkS")
		)
		(fp_line
			(start -0.7874 -0.4064)
			(end -0.7874 0.4064)
			(stroke
				(width 0.1524)
				(type default)
			)
			(layer "B.SilkS")
		)
		(fp_line
			(start 0.7874 -0.4064)
			(end -0.7874 -0.4064)
			(stroke
				(width 0.1524)
				(type default)
			)
			(layer "B.SilkS")
		)
		(fp_line
			(start -0.67945 0.3048)
			(end -0.120396 0.3048)
			(stroke
				(width 0.1)
				(type default)
			)
			(layer "B.Fab")
		)
		(fp_line
			(start -0.120396 0.3048)
			(end -0.120396 0.2794)
			(stroke
				(width 0.1)
				(type default)
			)
			(layer "B.Fab")
		)
		(fp_line
			(start 0.12065 0.3048)
			(end 0.67945 0.3048)
			(stroke
				(width 0.1)
				(type default)
			)
			(layer "B.Fab")
		)
		(fp_line
			(start 0.67945 0.3048)
			(end 0.67945 -0.305054)
			(stroke
				(width 0.1)
				(type default)
			)
			(layer "B.Fab")
		)
		(fp_line
			(start -0.120396 0.2794)
			(end 0.12065 0.2794)
			(stroke
				(width 0.1)
				(type default)
			)
			(layer "B.Fab")
		)
		(fp_line
			(start 0.12065 0.2794)
			(end 0.12065 0.3048)
			(stroke
				(width 0.1)
				(type default)
			)
			(layer "B.Fab")
		)
		(fp_line
			(start -0.12065 -0.2794)
			(end -0.12065 -0.3048)
			(stroke
				(width 0.1)
				(type default)
			)
			(layer "B.Fab")
		)
		(fp_line
			(start 0.12065 -0.2794)
			(end -0.12065 -0.2794)
			(stroke
				(width 0.1)
				(type default)
			)
			(layer "B.Fab")
		)
		(fp_line
			(start -0.67945 -0.3048)
			(end -0.67945 0.3048)
			(stroke
				(width 0.1)
				(type default)
			)
			(layer "B.Fab")
		)
		(fp_line
			(start -0.12065 -0.3048)
			(end -0.67945 -0.3048)
			(stroke
				(width 0.1)
				(type default)
			)
			(layer "B.Fab")
		)
		(fp_line
			(start 0.12065 -0.305054)
			(end 0.12065 -0.2794)
			(stroke
				(width 0.1)
				(type default)
			)
			(layer "B.Fab")
		)
		(fp_line
			(start 0.67945 -0.305054)
			(end 0.12065 -0.305054)
			(stroke
				(width 0.1)
				(type default)
			)
			(layer "B.Fab")
		)
		(pad "1" smd circle
			(at 0.40005 0 90)
			(size 0 0)
			(layers "B.Cu" "B.Mask" "B.Paste")
			(net "PWRGD_DRAMPWRGD_CPU1_GH_R_LVC1")
		)
		(pad "2" smd circle
			(at -0.40005 0 90)
			(size 0 0)
			(layers "B.Cu" "B.Mask" "B.Paste")
			(net "PWRGD_DRAMPWRGD_CPU1_GH_LVC1_R2")
		)
	)
	(footprint ""
		(layer "B.Cu")
		(at 192.795906 -72.804528)
		(property "Reference" "C1827"
			(at 0 0 0)
			(layer "B.SilkS")
			(hide yes)
			(effects
				(font
					(size 1.27 1.27)
				)
				(justify mirror)
			)
		)
		(property "Value" ""
			(at 0 0 0)
			(layer "B.Fab")
			(effects
				(font
					(size 1.27 1.27)
				)
				(justify mirror)
			)
		)
		(duplicate_pad_numbers_are_jumpers no)
		(fp_line
			(start -0.7874 -0.4064)
			(end -0.7874 0.4064)
			(stroke
				(width 0.1524)
				(type default)
			)
			(layer "B.SilkS")
		)
		(fp_line
			(start -0.7874 0.4064)
			(end 0.7874 0.4064)
			(stroke
				(width 0.1524)
				(type default)
			)
			(layer "B.SilkS")
		)
		(fp_line
			(start 0.7874 -0.4064)
			(end -0.7874 -0.4064)
			(stroke
				(width 0.1524)
				(type default)
			)
			(layer "B.SilkS")
		)
		(fp_line
			(start 0.7874 0.4064)
			(end 0.7874 -0.4064)
			(stroke
				(width 0.1524)
				(type default)
			)
			(layer "B.SilkS")
		)
		(fp_line
			(start -0.67945 -0.3048)
			(end -0.67945 0.3048)
			(stroke
				(width 0.1)
				(type default)
			)
			(layer "B.Fab")
		)
		(fp_line
			(start -0.67945 0.3048)
			(end -0.120396 0.3048)
			(stroke
				(width 0.1)
				(type default)
			)
			(layer "B.Fab")
		)
		(fp_line
			(start -0.12065 -0.3048)
			(end -0.67945 -0.3048)
			(stroke
				(width 0.1)
				(type default)
			)
			(layer "B.Fab")
		)
		(fp_line
			(start -0.12065 -0.2794)
			(end -0.12065 -0.3048)
			(stroke
				(width 0.1)
				(type default)
			)
			(layer "B.Fab")
		)
		(fp_line
			(start -0.120396 0.2794)
			(end 0.12065 0.2794)
			(stroke
				(width 0.1)
				(type default)
			)
			(layer "B.Fab")
		)
		(fp_line
			(start -0.120396 0.3048)
			(end -0.120396 0.2794)
			(stroke
				(width 0.1)
				(type default)
			)
			(layer "B.Fab")
		)
		(fp_line
			(start 0.12065 -0.305054)
			(end 0.12065 -0.2794)
			(stroke
				(width 0.1)
				(type default)
			)
			(layer "B.Fab")
		)
		(fp_line
			(start 0.12065 -0.2794)
			(end -0.12065 -0.2794)
			(stroke
				(width 0.1)
				(type default)
			)
			(layer "B.Fab")
		)
		(fp_line
			(start 0.12065 0.2794)
			(end 0.12065 0.3048)
			(stroke
				(width 0.1)
				(type default)
			)
			(layer "B.Fab")
		)
		(fp_line
			(start 0.12065 0.3048)
			(end 0.67945 0.3048)
			(stroke
				(width 0.1)
				(type default)
			)
			(layer "B.Fab")
		)
		(fp_line
			(start 0.67945 -0.305054)
			(end 0.12065 -0.305054)
			(stroke
				(width 0.1)
				(type default)
			)
			(layer "B.Fab")
		)
		(fp_line
			(start 0.67945 0.3048)
			(end 0.67945 -0.305054)
			(stroke
				(width 0.1)
				(type default)
			)
			(layer "B.Fab")
		)
		(pad "1" smd circle
			(at 0.40005 0 180)
			(size 0 0)
			(layers "B.Cu" "B.Mask" "B.Paste")
			(net "P3V3_AUX")
		)
		(pad "2" smd circle
			(at -0.40005 0 180)
			(size 0 0)
			(layers "B.Cu" "B.Mask" "B.Paste")
			(net "GND")
		)
	)
)
